G04*
G04 #@! TF.GenerationSoftware,Altium Limited,Altium Designer,23.7.1 (13)*
G04*
G04 Layer_Color=16711935*
%FSLAX25Y25*%
%MOIN*%
G70*
G04*
G04 #@! TF.SameCoordinates,AF00DCEB-AC48-4C7C-91EA-99F42E284231*
G04*
G04*
G04 #@! TF.FilePolarity,Positive*
G04*
G01*
G75*
%ADD15C,0.00787*%
D15*
X594109Y-289839D02*
Y-281680D01*
Y-289839D02*
X598331D01*
Y-281680D01*
X594109D02*
X598331D01*
X546046Y-274828D02*
Y-268874D01*
X542896D02*
X546046D01*
X542896Y-274828D02*
Y-268874D01*
Y-274828D02*
X546046D01*
X582441Y-280469D02*
Y-274515D01*
X579291D02*
X582441D01*
X579291Y-280469D02*
Y-274515D01*
Y-280469D02*
X582441D01*
X578755Y-289446D02*
Y-281286D01*
Y-289446D02*
X582977D01*
Y-281286D01*
X578755D02*
X582977D01*
X553959Y-279180D02*
X559912D01*
X553959Y-282330D02*
Y-279180D01*
Y-282330D02*
X559912D01*
Y-279180D01*
X586503Y-282847D02*
X592802D01*
Y-277138D01*
X586503D02*
X592802D01*
X586503Y-282847D02*
Y-277138D01*
X597795Y-281256D02*
Y-275303D01*
X594646D02*
X597795D01*
X594646Y-281256D02*
Y-275303D01*
Y-281256D02*
X597795D01*
X476298Y-303364D02*
Y-297410D01*
Y-303364D02*
X479447D01*
Y-297410D01*
X476298D02*
X479447D01*
X483292Y-267323D02*
Y-264173D01*
X477338Y-267323D02*
X483292D01*
X477338D02*
Y-264173D01*
X483292D01*
X188189Y-91511D02*
X191339D01*
Y-97465D02*
Y-91511D01*
X188189Y-97465D02*
X191339D01*
X188189D02*
Y-91511D01*
X150176Y6920D02*
X153325D01*
Y967D02*
Y6920D01*
X150176Y967D02*
X153325D01*
X150176D02*
Y6920D01*
X500221Y-253937D02*
Y-250787D01*
X494268Y-253937D02*
X500221D01*
X494268D02*
Y-250787D01*
X500221D01*
X504701Y-261711D02*
Y-258561D01*
X510654D01*
Y-261711D02*
Y-258561D01*
X504701Y-261711D02*
X510654D01*
X500614Y-261417D02*
Y-258268D01*
X494661Y-261417D02*
X500614D01*
X494661D02*
Y-258268D01*
X500614D01*
X568922Y-262694D02*
Y-259544D01*
X562968Y-262694D02*
X568922D01*
X562968D02*
Y-259544D01*
X568922D01*
X570350Y-262697D02*
Y-259547D01*
X576303D01*
Y-262697D02*
Y-259547D01*
X570350Y-262697D02*
X576303D01*
X207874Y-221D02*
X211024D01*
X207874D02*
Y5733D01*
X211024D01*
Y-221D02*
Y5733D01*
X202264Y-5929D02*
X205413D01*
X202264D02*
Y24D01*
X205413D01*
Y-5929D02*
Y24D01*
X212598Y-6126D02*
X215748D01*
X212598D02*
Y-173D01*
X215748D01*
Y-6126D02*
Y-173D01*
X202962Y-72023D02*
X206112D01*
Y-77977D02*
Y-72023D01*
X202962Y-77977D02*
X206112D01*
X202962D02*
Y-72023D01*
X212598Y-71826D02*
X215748D01*
Y-77780D02*
Y-71826D01*
X212598Y-77780D02*
X215748D01*
X212598D02*
Y-71826D01*
X406890Y-127953D02*
X413583D01*
X406890Y-131102D02*
Y-127953D01*
Y-131102D02*
X413583D01*
Y-127953D01*
X411668Y-122298D02*
X419828D01*
X411668Y-126521D02*
Y-122298D01*
Y-126521D02*
X419828D01*
Y-122298D01*
X425756Y-130566D02*
X434086D01*
X425756Y-134788D02*
Y-130566D01*
Y-134788D02*
X434086D01*
Y-130566D01*
X55249Y-36909D02*
X58399D01*
X55249D02*
Y-30217D01*
X58399D01*
Y-36909D02*
Y-30217D01*
X108913Y-14031D02*
X117072D01*
X108913Y-18253D02*
Y-14031D01*
Y-18253D02*
X117072D01*
Y-14031D01*
X91590Y-79277D02*
Y-75054D01*
X99749D01*
Y-79277D02*
Y-75054D01*
X91590Y-79277D02*
X99749D01*
X107087Y-43222D02*
X110236D01*
Y-49175D02*
Y-43222D01*
X107087Y-49175D02*
X110236D01*
X107087D02*
Y-43222D01*
X280315Y-192299D02*
X283465D01*
Y-198252D02*
Y-192299D01*
X280315Y-198252D02*
X283465D01*
X280315D02*
Y-192299D01*
X336393Y-291339D02*
X342347D01*
X336393Y-294488D02*
Y-291339D01*
Y-294488D02*
X342347D01*
Y-291339D01*
X317496Y-292126D02*
X323449D01*
X317496Y-295276D02*
Y-292126D01*
Y-295276D02*
X323449D01*
Y-292126D01*
X322614Y-238189D02*
X328567D01*
X322614Y-241339D02*
Y-238189D01*
Y-241339D02*
X328567D01*
Y-238189D01*
X374976Y-234547D02*
X380929D01*
Y-231398D01*
X374976D02*
X380929D01*
X374976Y-234547D02*
Y-231398D01*
X550787Y-327067D02*
X563386D01*
X550787Y-333563D02*
Y-327067D01*
Y-333563D02*
X563386D01*
Y-327067D01*
X526920Y-332085D02*
X539518D01*
Y-325589D01*
X526920D02*
X539518D01*
X526920Y-332085D02*
Y-325589D01*
X559842Y-313090D02*
X572441D01*
Y-306594D01*
X559842D02*
X572441D01*
X559842Y-313090D02*
Y-306594D01*
X526920Y-315521D02*
X539518D01*
Y-309024D01*
X526920D02*
X539518D01*
X526920Y-315521D02*
Y-309024D01*
X115748Y-32972D02*
X128347D01*
X115748Y-39469D02*
Y-32972D01*
Y-39469D02*
X128347D01*
Y-32972D01*
X119104Y-77823D02*
X131703D01*
Y-71326D01*
X119104D02*
X131703D01*
X119104Y-77823D02*
Y-71326D01*
X154332Y-74321D02*
Y-67824D01*
X141734Y-74321D02*
X154332D01*
X141734D02*
Y-67824D01*
X154332D01*
X145384Y-39419D02*
X151880D01*
Y-52017D02*
Y-39419D01*
X145384Y-52017D02*
X151880D01*
X145384D02*
Y-39419D01*
X610015Y-240158D02*
X615969D01*
Y-237008D01*
X610015D02*
X615969D01*
X610015Y-240158D02*
Y-237008D01*
X611349Y-232677D02*
X617303D01*
Y-229528D01*
X611349D02*
X617303D01*
X611349Y-232677D02*
Y-229528D01*
X611373Y-304232D02*
X617170D01*
Y-301279D01*
X611373D02*
X617170D01*
X611373Y-304232D02*
Y-301279D01*
X381429Y-132677D02*
X390484D01*
X381429Y-137402D02*
Y-132677D01*
Y-137402D02*
X390484D01*
Y-132677D01*
X66890Y-60501D02*
Y-51446D01*
X62165D02*
X66890D01*
X62165Y-60501D02*
Y-51446D01*
Y-60501D02*
X66890D01*
X93952Y-42771D02*
X98174D01*
Y-50930D02*
Y-42771D01*
X93952Y-50930D02*
X98174D01*
X93952D02*
Y-42771D01*
X99606Y-41929D02*
X104331D01*
Y-50984D02*
Y-41929D01*
X99606Y-50984D02*
X104331D01*
X99606D02*
Y-41929D01*
X606496Y-62598D02*
X615551D01*
X606496Y-67323D02*
Y-62598D01*
Y-67323D02*
X615551D01*
Y-62598D01*
X148515Y-122736D02*
X154312D01*
X148515Y-125689D02*
Y-122736D01*
Y-125689D02*
X154312D01*
Y-122736D01*
X162598Y-106102D02*
Y-97047D01*
Y-106102D02*
X167323D01*
Y-97047D01*
X162598D02*
X167323D01*
X151038Y-105655D02*
Y-97495D01*
Y-105655D02*
X155261D01*
Y-97495D01*
X151038D02*
X155261D01*
X160236Y-102966D02*
Y-97013D01*
X157087D02*
X160236D01*
X157087Y-102966D02*
Y-97013D01*
Y-102966D02*
X160236D01*
M02*
